# OAM Pin map rev 1.0.xlsx — OCP Generic Pin Map (pin-map)
| OCP Compute Accelerator Mezzanine Connector Pin map Top-down view of mezzanine module with ASIC/GPU mounted on top side & both connectors mounted on bottom side |  |  |  |  |  |  |  |  |  |  |  |  |  |  |  |  |  |  |  |  |  |  |  |  |  |  |  |  |  |  |  |  |  |
| CONNECTOR #0 |  |  |  |  |  |  |  |  |  |  |  |  |  |  |  |  |  |  |  |  |  | CONNECTOR #1 |  |  |  |  |  |  |  |  |  |  |  |
|  | A | B | C | D | E | F | G | H | J | K | L |  |  |  |  |  |  |  |  |  |  |  | A | B | C | D | E | F | G | H | J | K | L |
| 1 |  |  | P3V3 | PERST# | GND | RFU | PVREF | HOST_PWRGD | GND |  |  |  |  |  |  |  |  |  |  |  |  | 1 |  |  | GND | CONN1_MODPRS# | GND | CONN1_RESET# | GND | CONN1_YELLOW_LED | GND |  |  |
| 2 |  |  | P3V3 | WARMRST# | GND | RFU | PVREF | MODULE_PWRGD | GND |  |  |  |  |  |  |  |  |  |  |  |  | 2 |  |  | GND | CONN1_MODSEL# | GND | CONN1_GREEN_LED | GND | CONN2_INITMODE | GND |  |  |
| 3 | MANF_MODE# | GND | PWRBRK# | GND | UART_TXD | GND | I2C_D | GND | SMBus_SLV_CLK | GND | SMBus_SLV_D |  |  |  |  |  |  |  |  |  |  | 3 | CONN1_INITMODE | GND | RFU | GND | S7_TX15N | GND | RFU | GND | RFU | GND | CONN2_INT# |
| 4 | FW_RECOVERY# | GND | TEST_MODE# | GND | UART_RXD | GND | I2C _CLK | GND | PRSNT0# | GND | SLV_ALERT# |  |  |  |  |  |  |  |  |  |  | 4 | CONN1_INT# | GND | RFU | GND | S7_TX15P | GND | RFU | GND | RFU | GND | CONN2_MODPRS# |
| 5 | GND | S1_RX15P | GND | S1_RX7P | GND | RFU | GND | S1_TX15P | GND | S1_TX7P | GND |  |  |  |  |  |  |  |  |  |  | 5 | GND | RFU | GND | S7_TX14N | GND | CONN2_MODSEL# | GND | RFU | GND | S7_RX15N | GND |
| 6 | GND | S1_RX15N | GND | S1_RX7N | GND | MODULE_ID[4] | GND | S1_TX15N | GND | S1_TX7N | GND |  |  |  |  |  |  |  |  |  |  | 6 | GND | RFU | GND | S7_TX14P | GND | CONN2_RESET# | GND | RFU | GND | S7_RX15P | GND |
| 7 | S1_RX13P | GND | S1_RX14P | GND | S1_RX6P | GND | S1_TX13P | GND | S1_TX14P | GND | S1_TX6P |  |  |  |  |  |  |  |  |  |  | 7 | RFU | GND | RFU | GND | S7_TX13N | GND | RFU | GND | S7_RX13N | GND | S7_RX14N |
| 8 | S1_RX13N | GND | S1_RX14N | GND | S1_RX6N | GND | S1_TX13N | GND | S1_TX14N | GND | S1_TX6N |  |  |  |  |  |  |  |  |  |  | 8 | RFU | GND | RFU | GND | S7_TX13P | GND | RFU | GND | S7_RX13P | GND | S7_RX14P |
| 9 | GND | S1_RX12P | GND | S1_RX5P | GND | MODULE_ID[3] | GND | S1_TX12P | GND | S1_TX5P | GND |  |  |  |  |  |  |  |  |  |  | 9 | GND | S7_TX7N | GND | S7_TX12N | GND | CONN2_GREEN_LED | GND | S7_RX7N | GND | S7_RX12N | GND |
| 10 | GND | S1_RX12N | GND | S1_RX5N | GND | MODULE_ID[2] | GND | S1_TX12N | GND | S1_TX5N | GND |  |  |  |  |  |  |  |  |  |  | 10 | GND | S7_TX7P | GND | S7_TX12P | GND | CONN2_YELLOW_LED | GND | S7_RX7P | GND | S7_RX12P | GND |
| 11 | S1_RX10P | GND | S1_RX11P | GND | S1_RX4P | GND | S1_TX10P | GND | S1_TX11P | GND | S1_TX4P |  |  |  |  |  |  |  |  |  |  | 11 | S7_TX5N | GND | S7_TX6N | GND | S7_TX11N | GND | S7_RX5N | GND | S7_RX6N | GND | S7_RX11N |
| 12 | S1_RX10N | GND | S1_RX11N | GND | S1_RX4N | GND | S1_TX10N | GND | S1_TX11N | GND | S1_TX4N |  |  |  |  |  |  |  |  |  |  | 12 | S7_TX5P | GND | S7_TX6P | GND | S7_TX11P | GND | S7_RX5P | GND | S7_RX6P | GND | S7_RX11P |
| 13 | GND | S1_RX9P | GND | S1_RX3P | GND | MODULE_ID[1] | GND | S1_TX9P | GND | S1_TX3P | GND |  |  |  |  |  |  |  |  |  |  | 13 | GND | S7_TX4N | GND | S7_TX10N | GND | TEST10 | GND | S7_RX4N | GND | S7_RX10N | GND |
| 14 | GND | S1_RX9N | GND | S1_RX3N | GND | MODULE_ID[0] | GND | S1_TX9N | GND | S1_TX3N | GND |  |  |  |  |  |  |  |  |  |  | 14 | GND | S7_TX4P | GND | S7_TX10P | GND | TEST11 | GND | S7_RX4P | GND | S7_RX10P | GND |
| 15 | S1_RX8P | GND | S1_RX1P | GND | S1_RX2P | GND | S1_TX8P | GND | S1_TX1P | GND | S1_TX2P |  |  |  |  |  |  |  |  |  |  | 15 | S7_TX2N | GND | S7_TX3N | GND | S7_TX9N | GND | S7_RX2N | GND | S7_RX3N | GND | S7_RX9N |
| 16 | S1_RX8N | GND | S1_RX1N | GND | S1_RX2N | GND | S1_TX8N | GND | S1_TX1N | GND | S1_TX2N |  |  |  |  |  |  |  |  |  |  | 16 | S7_TX2P | GND | S7_TX3P | GND | S7_TX9P | GND | S7_RX2P | GND | S7_RX3P | GND | S7_RX9P |
| 17 | GND | S2_RX15P | GND | S1_RX0P | GND | JTAG0 _TDI | GND | S2_TX15P | GND | S1_TX0P | GND |  |  |  |  |  |  |  |  |  |  | 17 | GND | S7_TX1N | GND | S7_TX8N | GND | TEST12 | GND | S7_RX1N | GND | S7_RX8N | GND |
| 18 | GND | S2_RX15N | GND | S1_RX0N | GND | JTAG0_TMS | GND | S2_TX15N | GND | S1_TX0N | GND |  |  |  |  |  |  |  |  |  |  | 18 | GND | S7_TX1P | GND | S7_TX8P | GND | TEST13 | GND | S7_RX1P | GND | S7_RX8P | GND |
| 19 | S2_RX13P | GND | S2_RX14P | GND | S2_RX7P | GND | S2_TX13P | GND | S2_TX14P | GND | S2_TX7P |  |  |  |  |  |  |  |  |  |  | 19 | S7_TX0N | GND | S6_TX0N | GND | S6_TX8N | GND | S7_RX0N | GND | S6_RX0N | GND | S6_RX8N |
| 20 | S2_RX13N | GND | S2_RX14N | GND | S2_RX7N | GND | S2_TX13N | GND | S2_TX14N | GND | S2_TX7N |  |  |  |  |  |  |  |  |  |  | 20 | S7_TX0P | GND | S6_TX0P | GND | S6_TX8P | GND | S7_RX0P | GND | S6_RX0P | GND | S6_RX8P |
| 21 | GND | S2_RX12P | GND | S2_RX6P | GND | JTAG0_TCK | GND | S2_TX12P | GND | S2_TX6P | GND |  |  |  |  |  |  |  |  |  |  | 21 | GND | S6_TX1N | GND | S6_TX9N | GND | TEST14 | GND | S6_RX1N | GND | S6_RX9N | GND |
| 22 | GND | S2_RX12N | GND | S2_RX6N | GND | JTAG0_TRST | GND | S2_TX12N | GND | S2_TX6N | GND |  |  |  |  |  |  |  |  |  |  | 22 | GND | S6_TX1P | GND | S6_TX9P | GND | RFU | GND | S6_RX1P | GND | S6_RX9P | GND |
| 23 | S2_RX11P | GND | S2_RX4P | GND | S2_RX5P | GND | S2_TX11P | GND | S2_TX4P | GND | S2_TX5P |  |  |  |  |  |  |  |  |  |  | 23 | S6_TX3N | GND | S6_TX2N | GND | S6_TX10N | GND | S6_RX3N | GND | S6_RX2N | GND | S6_RX10N |
| 24 | S2_RX11N | GND | S2_RX4N | GND | S2_RX5N | GND | S2_TX11N | GND | S2_TX4N | GND | S2_TX5N |  |  |  |  |  |  |  |  |  |  | 24 | S6_TX3P | GND | S6_TX2P | GND | S6_TX10P | GND | S6_RX3P | GND | S6_RX2P | GND | S6_RX10P |
| 25 | GND | S2_RX10P | GND | S2_RX3P | GND | JTAG0_TDO | GND | S2_TX10P | GND | S2_TX3P | GND |  |  |  |  |  |  |  |  |  |  | 25 | GND | S6_TX4N | GND | S6_TX11N | GND | PWRRDT#0 | GND | S6_RX4N | GND | S6_RX11N | GND |
| 26 | GND | S2_RX10N | GND | S2_RX3N | GND | TEST0 | GND | S2_TX10N | GND | S2_TX3N | GND |  |  |  |  |  |  |  |  |  |  | 26 | GND | S6_TX4P | GND | S6_TX11P | GND | PWRRDT#1 | GND | S6_RX4P | GND | S6_RX11P | GND |
| 27 | S2_RX9P | GND | S2_RX1P | GND | S2_RX2P | GND | S2_TX9P | GND | S2_TX1P | GND | S2_TX2P |  |  |  |  |  |  |  |  |  |  | 27 | S6_TX5N | GND | S6_TX13N | GND | S6_TX12N | GND | S6_RX6N | GND | S6_RX5N | GND | S6_RX12N |
| 28 | S2_RX9N | GND | S2_RX1N | GND | S2_RX2N | GND | S2_TX9N | GND | S2_TX1N | GND | S2_TX2N |  |  |  |  |  |  |  |  |  |  | 28 | S6_TX5P | GND | S6_TX13P | GND | S6_TX12P | GND | S6_RX6P | GND | S6_RX5P | GND | S6_RX12P |
| 29 | GND | S2_RX8P | GND | S2_RX0P | GND | TEST1 | GND | S2_TX8P | GND | S2_TX0P | GND |  |  |  |  |  |  |  |  |  |  | 29 | GND | S6_TX6N | GND | S6_TX14N | GND | RFU | GND | S6_RX7N | GND | S6_RX13N | GND |
| 30 | GND | S2_RX8N | GND | S2_RX0N | GND | TEST2 | GND | S2_TX8N | GND | S2_TX0N | GND |  |  |  |  |  |  |  |  |  |  | 30 | GND | S6_TX6P | GND | S6_TX14P | GND | RFU | GND | S6_RX7P | GND | S6_RX13P | GND |
| 31 | S3_RX14P | GND | S3_RX15P | GND | S3_RX7P | GND | S3_TX14P | GND | S3_TX15P | GND | S3_TX7P |  |  |  |  |  |  |  |  |  |  | 31 | S6_TX7N | GND | S6_TX15N | GND | RFU | GND | RFU | GND | S6_RX15N | GND | S6_RX14N |
| 32 | S3_RX14N | GND | S3_RX15N | GND | S3_RX7N | GND | S3_TX14N | GND | S3_TX15N | GND | S3_TX7N |  |  |  |  |  |  |  |  |  |  | 32 | S6_TX7P | GND | S6_TX15P | GND | RFU | GND | RFU | GND | S6_RX15P | GND | S6_RX14P |
| 33 | GND | S3_RX13P | GND | S3_RX6P | GND | TEST3 | GND | S3_TX13P | GND | S3_TX6P | GND |  |  |  |  |  |  |  |  |  |  | 33 | GND | S5_TX0N | GND | S5_TX8N | GND | RFU | GND | S5_RX0N | GND | S5_RX8N | GND |
| 34 | GND | S3_RX13N | GND | S3_RX6N | GND | TEST4 | GND | S3_TX13N | GND | S3_TX6N | GND |  |  |  |  |  |  |  |  |  |  | 34 | GND | S5_TX0P | GND | S5_TX8P | GND | RFU | GND | S5_RX0P | GND | S5_RX8P | GND |
| 35 | S3_RX11P | GND | S3_RX12P | GND | S3_RX5P | GND | S3_TX12P | GND | S3_TX4P | GND | S3_TX5P |  |  |  |  |  |  |  |  |  |  | 35 | S5_TX2N | GND | S5_TX1N | GND | S5_TX9N | GND | S5_RX2N | GND | S5_RX1N | GND | S5_RX9N |
| 36 | S3_RX11N | GND | S3_RX12N | GND | S3_RX5N | GND | S3_TX12N | GND | S3_TX4N | GND | S3_TX5N |  |  |  |  |  |  |  |  |  |  | 36 | S5_TX2P | GND | S5_TX1P | GND | S5_TX9P | GND | S5_RX2P | GND | S5_RX1P | GND | S5_RX9P |
| 37 | GND | S3_RX10P | GND | S3_RX4P | GND | TEST5 | GND | S3_TX11P | GND | S3_TX3P | GND |  |  |  |  |  |  |  |  |  |  | 37 | GND | S5_TX3N | GND | S5_TX10N | GND | RFU | GND | S5_RX3N | GND | S5_RX10N | GND |
| 38 | GND | S3_RX10N | GND | S3_RX4N | GND | TEST6 | GND | S3_TX11N | GND | S3_TX3N | GND |  |  |  |  |  |  |  |  |  |  | 38 | GND | S5_TX3P | GND | S5_TX10P | GND | RFU | GND | S5_RX3P | GND | S5_RX10P | GND |
| 39 | S3_RX9P | GND | S3_RX2P | GND | S3_RX3P | GND | S3_TX10P | GND | S3_TX1P | GND | S3_TX2P |  |  |  |  |  |  |  |  |  |  | 39 | S5_TX4N | GND | S5_TX11N | GND | RFU | GND | S5_RX5N | GND | S5_RX4N | GND | S5_RX11N |
| 40 | S3_RX9N | GND | S3_RX2N | GND | S3_RX3N | GND | S3_TX10N | GND | S3_TX1N | GND | S3_TX2N |  |  |  |  |  |  |  |  |  |  | 40 | S5_TX4P | GND | S5_TX11P | GND | RFU | GND | S5_RX5P | GND | S5_RX4P | GND | S5_RX11P |
| 41 | GND | S3_RX8P | GND | S3_RX1P | GND | TEST7 | GND | S3_TX9P | GND | S3_TX0P | GND |  |  |  |  |  |  |  |  |  |  | 41 | GND | S5_TX5N | GND | S5_TX12N | GND | RFU | GND | S5_RX6N | GND | S5_RX12N | GND |
| 42 | GND | S3_RX8N | GND | S3_RX1N | GND | TEST8 | GND | S3_TX9N | GND | S3_TX0N | GND |  |  |  |  |  |  |  |  |  |  | 42 | GND | S5_TX5P | GND | S5_TX12P | GND | RFU | GND | S5_RX6P | GND | S5_RX12P | GND |
| 43 | PCIE_RX1P | GND | PCIE_RX0P | GND | S3_RX0P | GND | S3_TX8P | GND | PCIE_TX1P | GND | PCIE_TX0P |  |  |  |  |  |  |  |  |  |  | 43 | S5_TX6N | GND | S5_TX14N | GND | S5_TX13N | GND | S5_RX7N | GND | S5_RX14N | GND | S5_RX13N |
| 44 | PCIE_RX1N | GND | PCIE_RX0N | GND | S3_RX0N | GND | S3_TX8N | GND | PCIE_TX1N | GND | PCIE_TX0N |  |  |  |  |  |  |  |  |  |  | 44 | S5_TX6P | GND | S5_TX14P | GND | S5_TX13P | GND | S5_RX7P | GND | S5_RX14P | GND | S5_RX13P |
| 45 | GND | PCIE_RX3P | GND | PCIE_RX2P | GND | PE_REFCLKP | GND | PCIE_TX3P | GND | PCIE_TX2P | GND |  |  |  |  |  |  |  |  |  |  | 45 | GND | S5_TX7N | GND | S5_TX15N | GND | RFU | GND | AUX_156M_REFCLKP | GND | S5_RX15N | GND |
| 46 | GND | PCIE_RX3N | GND | PCIE_RX2N | GND | PE_REFCLKN | GND | PCIE_TX3N | GND | PCIE_TX2N | GND |  |  |  |  |  |  |  |  |  |  | 46 | GND | S5_TX7P | GND | S5_TX15P | GND | LINK_CONFIG[4] | GND | AUX_156M_REFCLKN | GND | S5_RX15P | GND |
| 47 | PCIE_RX6P | GND | PCIE_RX5P | GND | PCIE_RX4P | GND | PCIE_TX6P | GND | PCIE_TX5P | GND | PCIE_TX4P |  |  |  |  |  |  |  |  |  |  | 47 | S4_TX1N | GND | S4_TX0N | GND | S4_TX8N | GND | S4_RX0N | GND | S4_RX9N | GND | S4_RX8N |
| 48 | PCIE_RX6N | GND | PCIE_RX5N | GND | PCIE_RX4N | GND | PCIE_TX6N | GND | PCIE_TX5N | GND | PCIE_TX4N |  |  |  |  |  |  |  |  |  |  | 48 | S4_TX1P | GND | S4_TX0P | GND | S4_TX8P | GND | S4_RX0P | GND | S4_RX9P | GND | S4_RX8P |
| 49 | GND | PCIE_RX8P | GND | PCIE_RX7P | GND | TEST9 | GND | PCIE_TX8P | GND | PCIE_TX7P | GND |  |  |  |  |  |  |  |  |  |  | 49 | GND | S4_TX2N | GND | S4_TX9N | GND | LINK_CONFIG[3] | GND | S4_RX1N | GND | S4_RX10N | GND |
| 50 | GND | PCIE_RX8N | GND | PCIE_RX7N | GND | RFU | GND | PCIE_TX8N | GND | PCIE_TX7N | GND |  |  |  |  |  |  |  |  |  |  | 50 | GND | S4_TX2P | GND | S4_TX9P | GND | LINK_CONFIG[2] | GND | S4_RX1P | GND | S4_RX10P | GND |
| 51 | PCIE_RX11P | GND | PCIE_RX10P | GND | PCIE_RX9P | GND | PCIE_TX11P | GND | PCIE_TX10P | GND | PCIE_TX9P |  |  |  |  |  |  |  |  |  |  | 51 | S4_TX3N | GND | S4_TX11N | GND | S4_TX10N | GND | S4_RX2N | GND | S4_RX12N | GND | S4_RX11N |
| 52 | PCIE_RX11N | GND | PCIE_RX10N | GND | PCIE_RX9N | GND | PCIE_TX11N | GND | PCIE_TX10N | GND | PCIE_TX9N |  |  |  |  |  |  |  |  |  |  | 52 | S4_TX3P | GND | S4_TX11P | GND | S4_TX10P | GND | S4_RX2P | GND | S4_RX12P | GND | S4_RX11P |
| 53 | GND | PCIE_RX13P | GND | PCIE_RX12P | GND | GND | GND | PCIE_TX13P | GND | PCIE_TX12P | GND |  |  |  |  |  |  |  |  |  |  | 53 | GND | S4_TX4N | GND | S4_TX12N | GND | LINK_CONFIG[1] | GND | S4_RX3N | GND | S4_RX13N | GND |
| 54 | GND | PCIE_RX13N | GND | PCIE_RX12N | GND | GND | GND | PCIE_TX13N | GND | PCIE_TX12N | GND |  |  |  |  |  |  |  |  |  |  | 54 | GND | S4_TX4P | GND | S4_TX12P | GND | LINK_CONFIG[0] | GND | S4_RX3P | GND | S4_RX13P | GND |
| 55 | PCIE_RX15P | GND | PCIE_RX14P | GND | GND | GND | GND | GND | PCIE_TX15P | GND | PCIE_TX14P |  |  |  |  |  |  |  |  |  |  | 55 | S4_TX5N | GND | S4_TX14N | GND | S4_TX13N | GND | SCALE_DEBUG_EN | GND | S4_RX4N | GND | S4_RX14N |
| 56 | PCIE_RX15N | GND | PCIE_RX14N | GND | GND | GND | GND | GND | PCIE_TX15N | GND | PCIE_TX14N |  |  |  |  |  |  |  |  |  |  | 56 | S4_TX5P | GND | S4_TX14P | GND | S4_TX13P | GND | DEBUG_PORT_PRSNT# | GND | S4_RX4P | GND | S4_RX14P |
| 57 | GND | GND | GND | GND | GND | GND | GND | GND | GND | GND | GND |  |  |  |  |  |  |  |  |  |  | 57 | GND | S4_TX6N | GND | S4_TX15N | GND | PLINK_CAP | GND | S4_RX5N | GND | S4_RX15N | GND |
| 58 | GND | GND | GND | GND | GND | GND | GND | DO_NOT_USE | GND | DO_NOT_USE | GND |  |  |  |  |  |  |  |  |  |  | 58 | GND | S4_TX6P | GND | S4_TX15P | GND | DWN_PERST# | GND | S4_RX5P | GND | S4_RX15P | GND |
| 59 | P12V1 | P12V2 | P12V2 | P12V2 | P12V2 | P12V2 | GND | P48V | GND | P48V | GND |  |  |  |  |  |  |  |  |  |  | 59 | S4_TX7N | GND | RFU | GND | DWN_REFCLKP | GND | S4_RX7N | GND | S4_RX6N | GND | JTAG1 _TRST |
| 60 | P12V1 | P12V2 | P12V2 | P12V2 | P12V2 | P12V2 | GND | P48V | DO_NOT_USE | P48V | DO_NOT_USE |  |  |  |  |  |  |  |  |  |  | 60 | S4_TX7P | GND | RFU | GND | DWN_REFCLKN | GND | S4_RX7P | GND | S4_RX6P | GND | JTAG1 _TMS |
| 61 | P12V1 | P12V2 | P12V2 | P12V2 | P12V2 | P12V2 | GND | P48V | P48V | P48V | P48V |  |  |  |  |  |  |  |  |  |  | 61 | GND | PE_BIF[1] | GND | MNGMT_LINK0TN | GND | AUX_100M_REFCLKP | GND | MNGMT_LINK0RN | GND | JTAG1 _TCK | GND |
| 62 | P12V1 | P12V1 | P12V2 | P12V2 | P12V2 | P12V2 | GND | P48V | P48V | P48V | P48V |  |  |  |  |  |  |  |  |  |  | 62 | GND | PE_BIF[0] | GND | MNGMT_LINK0TP | GND | AUX_100M_REFCLKN | GND | MNGMT_LINK0RP | GND | JTAG1 _TDO | GND |
| 63 |  |  | P12V2 | P12V2 | P12V2 | P12V2 | GND | P48V | P48V |  |  |  |  |  |  |  |  |  |  |  |  | 63 |  |  | PRSNT1# | GND | MNGMT_LINK1TP | GND | MNGMT_LINK1RP | GND | JTAG1 _TDI |  |  |
| 64 |  |  | P12V2 | P12V2 | P12V2 | P12V2 | GND | P48V | P48V |  |  |  |  |  |  |  |  |  |  |  |  | 64 |  |  | THERMTRIP# | GND | MNGMT_LINK1TN | GND | MNGMT_LINK1RN | GND | RFU |  |  |
| CONNECTOR #0 |  |  |  |  |  |  |  |  |  |  |  |  |  |  |  |  |  |  |  |  |  | CONNECTOR #1 |  |  |  |  |  |  |  |  |  |  |  |
| P48V, P12V, P3V3, PLVIO, PCIE, SERDES 1/2/3, MISC |  |  |  |  |  |  |  |  |  |  |  |  |  |  |  |  |  |  |  |  |  | SERDES 4/5/6/7, MISC |  |  |  |  |  |  |  |  |  |  |  |
| NOTE: PCIE net naming is based on Host side interface |  |  |  |  |  |  |  |  |  |  |  |  |  |  |  |  |  |  |  |  |  |  |  |  |  |  |  |  |  |  |  |  |  |
|  | Connector #0 |  |  |  |  |  |  |  |  |  |  |  |  |  |  |  |  |  |  |  |  |  |  |  |  |  |  |  |  |  |  |  |  |
|  | Pin | Net |  | Pin | Net |  | Pin | Net |  | Pin | Net | Pin | Net | Pin | Net | Pin | Net | Pin | Net | Pin | Net |  | Pin | Net |  | Pin | Net |  |  |  |  |  |  |
|  |  |  |  |  |  |  | C1 | P3V3 |  | D1 | PERST# | E1 | GND | F1 | RFU | G1 | PVREF | H1 | HOST_PWRGD | J1 | GND |  |  |  |  |  |  |  |  |  |  |  |  |
|  |  |  |  |  |  |  | C2 | P3V3 |  | D2 | WARMRST# | E2 | GND | F2 | RFU | G2 | PVREF | H2 | MODULE_PWRGD | J2 | GND |  |  |  |  |  |  |  |  |  |  |  |  |
|  | A3 | MANF_MODE# |  | B3 | GND |  | C3 | PWRBRK# |  | D3 | GND | E3 | UART_TXD | F3 | GND | G3 | I2C_D | H3 | GND | J3 | SMBus_SLV_CLK |  | K3 | GND |  | L3 | SMBus_SLV_D |  |  |  |  |  |  |
|  | A4 | FW_RECOVERY# |  | B4 | GND |  | C4 | TEST_MODE# |  | D4 | GND | E4 | UART_RXD | F4 | GND | G4 | I2C _CLK | H4 | GND | J4 | PRSNT0# |  | K4 | GND |  | L4 | SLV_ALERT# |  |  |  |  |  |  |
|  | A5 | GND |  | B5 | S1_RX15P |  | C5 | GND |  | D5 | S1_RX7P | E5 | GND | F5 | RFU | G5 | GND | H5 | S1_TX15P | J5 | GND |  | K5 | S1_TX7P |  | L5 | GND |  |  |  |  |  |  |
|  | A6 | GND |  | B6 | S1_RX15N |  | C6 | GND |  | D6 | S1_RX7N | E6 | GND | F6 | MODULE_ID[4] | G6 | GND | H6 | S1_TX15N | J6 | GND |  | K6 | S1_TX7N |  | L6 | GND |  |  |  |  |  |  |
|  | A7 | S1_RX13P |  | B7 | GND |  | C7 | S1_RX14P |  | D7 | GND | E7 | S1_RX6P | F7 | GND | G7 | S1_TX13P | H7 | GND | J7 | S1_TX14P |  | K7 | GND |  | L7 | S1_TX6P |  |  |  |  |  |  |
|  | A8 | S1_RX13N |  | B8 | GND |  | C8 | S1_RX14N |  | D8 | GND | E8 | S1_RX6N | F8 | GND | G8 | S1_TX13N | H8 | GND | J8 | S1_TX14N |  | K8 | GND |  | L8 | S1_TX6N |  |  |  |  |  |  |
|  | A9 | GND |  | B9 | S1_RX12P |  | C9 | GND |  | D9 | S1_RX5P | E9 | GND | F9 | MODULE_ID[3] | G9 | GND | H9 | S1_TX12P | J9 | GND |  | K9 | S1_TX5P |  | L9 | GND |  |  |  |  |  |  |
|  | A10 | GND |  | B10 | S1_RX12N |  | C10 | GND |  | D10 | S1_RX5N | E10 | GND | F10 | MODULE_ID[2] | G10 | GND | H10 | S1_TX12N | J10 | GND |  | K10 | S1_TX5N |  | L10 | GND |  |  |  |  |  |  |
|  | A11 | S1_RX10P |  | B11 | GND |  | C11 | S1_RX11P |  | D11 | GND | E11 | S1_RX4P | F11 | GND | G11 | S1_TX10P | H11 | GND | J11 | S1_TX11P |  | K11 | GND |  | L11 | S1_TX4P |  |  |  |  |  |  |
|  | A12 | S1_RX10N |  | B12 | GND |  | C12 | S1_RX11N |  | D12 | GND | E12 | S1_RX4N | F12 | GND | G12 | S1_TX10N | H12 | GND | J12 | S1_TX11N |  | K12 | GND |  | L12 | S1_TX4N |  |  |  |  |  |  |
|  | A13 | GND |  | B13 | S1_RX9P |  | C13 | GND |  | D13 | S1_RX3P | E13 | GND | F13 | MODULE_ID[1] | G13 | GND | H13 | S1_TX9P | J13 | GND |  | K13 | S1_TX3P |  | L13 | GND |  |  |  |  |  |  |
|  | A14 | GND |  | B14 | S1_RX9N |  | C14 | GND |  | D14 | S1_RX3N | E14 | GND | F14 | MODULE_ID[0] | G14 | GND | H14 | S1_TX9N | J14 | GND |  | K14 | S1_TX3N |  | L14 | GND |  |  |  |  |  |  |
|  | A15 | S1_RX8P |  | B15 | GND |  | C15 | S1_RX1P |  | D15 | GND | E15 | S1_RX2P | F15 | GND | G15 | S1_TX8P | H15 | GND | J15 | S1_TX1P |  | K15 | GND |  | L15 | S1_TX2P |  |  |  |  |  |  |
|  | A16 | S1_RX8N |  | B16 | GND |  | C16 | S1_RX1N |  | D16 | GND | E16 | S1_RX2N | F16 | GND | G16 | S1_TX8N | H16 | GND | J16 | S1_TX1N |  | K16 | GND |  | L16 | S1_TX2N |  |  |  |  |  |  |
|  | A17 | GND |  | B17 | S2_RX15P |  | C17 | GND |  | D17 | S1_RX0P | E17 | GND | F17 | JTAG0 _TDI | G17 | GND | H17 | S2_TX15P | J17 | GND |  | K17 | S1_TX0P |  | L17 | GND |  |  |  |  |  |  |
|  | A18 | GND |  | B18 | S2_RX15N |  | C18 | GND |  | D18 | S1_RX0N | E18 | GND | F18 | JTAG0_TMS | G18 | GND | H18 | S2_TX15N | J18 | GND |  | K18 | S1_TX0N |  | L18 | GND |  |  |  |  |  |  |
|  | A19 | S2_RX13P |  | B19 | GND |  | C19 | S2_RX14P |  | D19 | GND | E19 | S2_RX7P | F19 | GND | G19 | S2_TX13P | H19 | GND | J19 | S2_TX14P |  | K19 | GND |  | L19 | S2_TX7P |  |  |  |  |  |  |
|  | A20 | S2_RX13N |  | B20 | GND |  | C20 | S2_RX14N |  | D20 | GND | E20 | S2_RX7N | F20 | GND | G20 | S2_TX13N | H20 | GND | J20 | S2_TX14N |  | K20 | GND |  | L20 | S2_TX7N |  |  |  |  |  |  |
|  | A21 | GND |  | B21 | S2_RX12P |  | C21 | GND |  | D21 | S2_RX6P | E21 | GND | F21 | JTAG0_TCK | G21 | GND | H21 | S2_TX12P | J21 | GND |  | K21 | S2_TX6P |  | L21 | GND |  |  |  |  |  |  |
|  | A22 | GND |  | B22 | S2_RX12N |  | C22 | GND |  | D22 | S2_RX6N | E22 | GND | F22 | JTAG0_TRST | G22 | GND | H22 | S2_TX12N | J22 | GND |  | K22 | S2_TX6N |  | L22 | GND |  |  |  |  |  |  |
|  | A23 | S2_RX11P |  | B23 | GND |  | C23 | S2_RX4P |  | D23 | GND | E23 | S2_RX5P | F23 | GND | G23 | S2_TX11P | H23 | GND | J23 | S2_TX4P |  | K23 | GND |  | L23 | S2_TX5P |  |  |  |  |  |  |
|  | A24 | S2_RX11N |  | B24 | GND |  | C24 | S2_RX4N |  | D24 | GND | E24 | S2_RX5N | F24 | GND | G24 | S2_TX11N | H24 | GND | J24 | S2_TX4N |  | K24 | GND |  | L24 | S2_TX5N |  |  |  |  |  |  |
|  | A25 | GND |  | B25 | S2_RX10P |  | C25 | GND |  | D25 | S2_RX3P | E25 | GND | F25 | JTAG0_TDO | G25 | GND | H25 | S2_TX10P | J25 | GND |  | K25 | S2_TX3P |  | L25 | GND |  |  |  |  |  |  |
|  | A26 | GND |  | B26 | S2_RX10N |  | C26 | GND |  | D26 | S2_RX3N | E26 | GND | F26 | TEST0 | G26 | GND | H26 | S2_TX10N | J26 | GND |  | K26 | S2_TX3N |  | L26 | GND |  |  |  |  |  |  |
|  | A27 | S2_RX9P |  | B27 | GND |  | C27 | S2_RX1P |  | D27 | GND | E27 | S2_RX2P | F27 | GND | G27 | S2_TX9P | H27 | GND | J27 | S2_TX1P |  | K27 | GND |  | L27 | S2_TX2P |  |  |  |  |  |  |
|  | A28 | S2_RX9N |  | B28 | GND |  | C28 | S2_RX1N |  | D28 | GND | E28 | S2_RX2N | F28 | GND | G28 | S2_TX9N | H28 | GND | J28 | S2_TX1N |  | K28 | GND |  | L28 | S2_TX2N |  |  |  |  |  |  |
|  | A29 | GND |  | B29 | S2_RX8P |  | C29 | GND |  | D29 | S2_RX0P | E29 | GND | F29 | TEST1 | G29 | GND | H29 | S2_TX8P | J29 | GND |  | K29 | S2_TX0P |  | L29 | GND |  |  |  |  |  |  |
|  | A30 | GND |  | B30 | S2_RX8N |  | C30 | GND |  | D30 | S2_RX0N | E30 | GND | F30 | TEST2 | G30 | GND | H30 | S2_TX8N | J30 | GND |  | K30 | S2_TX0N |  | L30 | GND |  |  |  |  |  |  |
|  | A31 | S3_RX14P |  | B31 | GND |  | C31 | S3_RX15P |  | D31 | GND | E31 | S3_RX7P | F31 | GND | G31 | S3_TX14P | H31 | GND | J31 | S3_TX15P |  | K31 | GND |  | L31 | S3_TX7P |  |  |  |  |  |  |
|  | A32 | S3_RX14N |  | B32 | GND |  | C32 | S3_RX15N |  | D32 | GND | E32 | S3_RX7N | F32 | GND | G32 | S3_TX14N | H32 | GND | J32 | S3_TX15N |  | K32 | GND |  | L32 | S3_TX7N |  |  |  |  |  |  |
|  | A33 | GND |  | B33 | S3_RX13P |  | C33 | GND |  | D33 | S3_RX6P | E33 | GND | F33 | TEST3 | G33 | GND | H33 | S3_TX13P | J33 | GND |  | K33 | S3_TX6P |  | L33 | GND |  |  |  |  |  |  |
|  | A34 | GND |  | B34 | S3_RX13N |  | C34 | GND |  | D34 | S3_RX6N | E34 | GND | F34 | TEST4 | G34 | GND | H34 | S3_TX13N | J34 | GND |  | K34 | S3_TX6N |  | L34 | GND |  |  |  |  |  |  |
|  | A35 | S3_RX11P |  | B35 | GND |  | C35 | S3_RX12P |  | D35 | GND | E35 | S3_RX5P | F35 | GND | G35 | S3_TX12P | H35 | GND | J35 | S3_TX4P |  | K35 | GND |  | L35 | S3_TX5P |  |  |  |  |  |  |
|  | A36 | S3_RX11N |  | B36 | GND |  | C36 | S3_RX12N |  | D36 | GND | E36 | S3_RX5N | F36 | GND | G36 | S3_TX12N | H36 | GND | J36 | S3_TX4N |  | K36 | GND |  | L36 | S3_TX5N |  |  |  |  |  |  |
|  | A37 | GND |  | B37 | S3_RX10P |  | C37 | GND |  | D37 | S3_RX4P | E37 | GND | F37 | TEST5 | G37 | GND | H37 | S3_TX11P | J37 | GND |  | K37 | S3_TX3P |  | L37 | GND |  |  |  |  |  |  |
|  | A38 | GND |  | B38 | S3_RX10N |  | C38 | GND |  | D38 | S3_RX4N | E38 | GND | F38 | TEST6 | G38 | GND | H38 | S3_TX11N | J38 | GND |  | K38 | S3_TX3N |  | L38 | GND |  |  |  |  |  |  |
|  | A39 | S3_RX9P |  | B39 | GND |  | C39 | S3_RX2P |  | D39 | GND | E39 | S3_RX3P | F39 | GND | G39 | S3_TX10P | H39 | GND | J39 | S3_TX1P |  | K39 | GND |  | L39 | S3_TX2P |  |  |  |  |  |  |
|  | A40 | S3_RX9N |  | B40 | GND |  | C40 | S3_RX2N |  | D40 | GND | E40 | S3_RX3N | F40 | GND | G40 | S3_TX10N | H40 | GND | J40 | S3_TX1N |  | K40 | GND |  | L40 | S3_TX2N |  |  |  |  |  |  |
|  | A41 | GND |  | B41 | S3_RX8P |  | C41 | GND |  | D41 | S3_RX1P | E41 | GND | F41 | TEST7 | G41 | GND | H41 | S3_TX9P | J41 | GND |  | K41 | S3_TX0P |  | L41 | GND |  |  |  |  |  |  |
|  | A42 | GND |  | B42 | S3_RX8N |  | C42 | GND |  | D42 | S3_RX1N | E42 | GND | F42 | TEST8 | G42 | GND | H42 | S3_TX9N | J42 | GND |  | K42 | S3_TX0N |  | L42 | GND |  |  |  |  |  |  |
|  | A43 | PCIE_RX1P |  | B43 | GND |  | C43 | PCIE_RX0P |  | D43 | GND | E43 | S3_RX0P | F43 | GND | G43 | S3_TX8P | H43 | GND | J43 | PCIE_TX1P |  | K43 | GND |  | L43 | PCIE_TX0P |  |  |  |  |  |  |
|  | A44 | PCIE_RX1N |  | B44 | GND |  | C44 | PCIE_RX0N |  | D44 | GND | E44 | S3_RX0N | F44 | GND | G44 | S3_TX8N | H44 | GND | J44 | PCIE_TX1N |  | K44 | GND |  | L44 | PCIE_TX0N |  |  |  |  |  |  |
|  | A45 | GND |  | B45 | PCIE_RX3P |  | C45 | GND |  | D45 | PCIE_RX2P | E45 | GND | F45 | PE_REFCLKP | G45 | GND | H45 | PCIE_TX3P | J45 | GND |  | K45 | PCIE_TX2P |  | L45 | GND |  |  |  |  |  |  |
|  | A46 | GND |  | B46 | PCIE_RX3N |  | C46 | GND |  | D46 | PCIE_RX2N | E46 | GND | F46 | PE_REFCLKN | G46 | GND | H46 | PCIE_TX3N | J46 | GND |  | K46 | PCIE_TX2N |  | L46 | GND |  |  |  |  |  |  |
|  | A47 | PCIE_RX6P |  | B47 | GND |  | C47 | PCIE_RX5P |  | D47 | GND | E47 | PCIE_RX4P | F47 | GND | G47 | PCIE_TX6P | H47 | GND | J47 | PCIE_TX5P |  | K47 | GND |  | L47 | PCIE_TX4P |  |  |  |  |  |  |
|  | A48 | PCIE_RX6N |  | B48 | GND |  | C48 | PCIE_RX5N |  | D48 | GND | E48 | PCIE_RX4N | F48 | GND | G48 | PCIE_TX6N | H48 | GND | J48 | PCIE_TX5N |  | K48 | GND |  | L48 | PCIE_TX4N |  |  |  |  |  |  |
|  | A49 | GND |  | B49 | PCIE_RX8P |  | C49 | GND |  | D49 | PCIE_RX7P | E49 | GND | F49 | TEST9 | G49 | GND | H49 | PCIE_TX8P | J49 | GND |  | K49 | PCIE_TX7P |  | L49 | GND |  |  |  |  |  |  |
|  | A50 | GND |  | B50 | PCIE_RX8N |  | C50 | GND |  | D50 | PCIE_RX7N | E50 | GND | F50 | RFU | G50 | GND | H50 | PCIE_TX8N | J50 | GND |  | K50 | PCIE_TX7N |  | L50 | GND |  |  |  |  |  |  |
|  | A51 | PCIE_RX11P |  | B51 | GND |  | C51 | PCIE_RX10P |  | D51 | GND | E51 | PCIE_RX9P | F51 | GND | G51 | PCIE_TX11P | H51 | GND | J51 | PCIE_TX10P |  | K51 | GND |  | L51 | PCIE_TX9P |  |  |  |  |  |  |
|  | A52 | PCIE_RX11N |  | B52 | GND |  | C52 | PCIE_RX10N |  | D52 | GND | E52 | PCIE_RX9N | F52 | GND | G52 | PCIE_TX11N | H52 | GND | J52 | PCIE_TX10N |  | K52 | GND |  | L52 | PCIE_TX9N |  |  |  |  |  |  |
|  | A53 | GND |  | B53 | PCIE_RX13P |  | C53 | GND |  | D53 | PCIE_RX12P | E53 | GND | F53 | GND | G53 | GND | H53 | PCIE_TX13P | J53 | GND |  | K53 | PCIE_TX12P |  | L53 | GND |  |  |  |  |  |  |
|  | A54 | GND |  | B54 | PCIE_RX13N |  | C54 | GND |  | D54 | PCIE_RX12N | E54 | GND | F54 | GND | G54 | GND | H54 | PCIE_TX13N | J54 | GND |  | K54 | PCIE_TX12N |  | L54 | GND |  |  |  |  |  |  |
|  | A55 | PCIE_RX15P |  | B55 | GND |  | C55 | PCIE_RX14P |  | D55 | GND | E55 | GND | F55 | GND | G55 | GND | H55 | GND | J55 | PCIE_TX15P |  | K55 | GND |  | L55 | PCIE_TX14P |  |  |  |  |  |  |
|  | A56 | PCIE_RX15N |  | B56 | GND |  | C56 | PCIE_RX14N |  | D56 | GND | E56 | GND | F56 | GND | G56 | GND | H56 | GND | J56 | PCIE_TX15N |  | K56 | GND |  | L56 | PCIE_TX14N |  |  |  |  |  |  |
|  | A57 | GND |  | B57 | GND |  | C57 | GND |  | D57 | GND | E57 | GND | F57 | GND | G57 | GND | H57 | GND | J57 | GND |  | K57 | GND |  | L57 | GND |  |  |  |  |  |  |
|  | A58 | GND |  | B58 | GND |  | C58 | GND |  | D58 | GND | E58 | GND | F58 | GND | G58 | GND | H58 | DO_NOT_USE | J58 | GND |  | K58 | DO_NOT_USE |  | L58 | GND |  |  |  |  |  |  |
|  | A59 | P12V1 |  | B59 | P12V2 |  | C59 | P12V2 |  | D59 | P12V2 | E59 | P12V2 | F59 | P12V2 | G59 | GND | H59 | P48V | J59 | GND |  | K59 | P48V |  | L59 | GND |  |  |  |  |  |  |
|  | A60 | P12V1 |  | B60 | P12V2 |  | C60 | P12V2 |  | D60 | P12V2 | E60 | P12V2 | F60 | P12V2 | G60 | GND | H60 | P48V | J60 | DO_NOT_USE |  | K60 | P48V |  | L60 | DO_NOT_USE |  |  |  |  |  |  |
|  | A61 | P12V1 |  | B61 | P12V2 |  | C61 | P12V2 |  | D61 | P12V2 | E61 | P12V2 | F61 | P12V2 | G61 | GND | H61 | P48V | J61 | P48V |  | K61 | P48V |  | L61 | P48V |  |  |  |  |  |  |
|  | A62 | P12V1 |  | B62 | P12V1 |  | C62 | P12V2 |  | D62 | P12V2 | E62 | P12V2 | F62 | P12V2 | G62 | GND | H62 | P48V | J62 | P48V |  | K62 | P48V |  | L62 | P48V |  |  |  |  |  |  |
|  |  |  |  |  |  |  | C63 | P12V2 |  | D63 | P12V2 | E63 | P12V2 | F63 | P12V2 | G63 | GND | H63 | P48V | J63 | P48V |  |  |  |  |  |  |  |  |  |  |  |  |
|  |  |  |  |  |  |  | C64 | P12V2 |  | D64 | P12V2 | E64 | P12V2 | F64 | P12V2 | G64 | GND | H64 | P48V | J64 | P48V |  |  |  |  |  |  |  |  |  |  |  |  |
|  | Connector #1 |  |  |  |  |  |  |  |  |  |  |  |  |  |  |  |  |  |  |  |  |  |  |  |  |  |  |  |  |  |  |  |  |
|  | Pin | Net |  | Pin | Net |  | Pin | Net |  | Pin | Net | Pin | Net | Pin | Net | Pin | Net | Pin | Net | Pin | Net |  | Pin | Net |  | Pin | Net |  |  |  |  |  |  |
|  |  |  |  |  |  |  | C1 | GND |  | D1 | CONN1_MODPRS# | E1 | GND | F1 | CONN1_RESET# | G1 | GND | H1 | CONN1_YELLOW_LED | J1 | GND |  |  |  |  |  |  |  |  |  |  |  |  |
|  |  |  |  |  |  |  | C2 | GND |  | D2 | CONN1_MODSEL# | E2 | GND | F2 | CONN1_GREEN_LED | G2 | GND | H2 | CONN2_INITMODE | J2 | GND |  |  |  |  |  |  |  |  |  |  |  |  |
|  | A3 | CONN1_INITMODE |  | B3 | GND |  | C3 | RFU |  | D3 | GND | E3 | S7_TX15N | F3 | GND | G3 | RFU | H3 | GND | J3 | PWRRDT#0 |  | K3 | GND |  | L3 | CONN2_INT# |  |  |  |  |  |  |
|  | A4 | CONN1_INT# |  | B4 | GND |  | C4 | RFU |  | D4 | GND | E4 | S7_TX15P | F4 | GND | G4 | RFU | H4 | GND | J4 | PWRRDT#1 |  | K4 | GND |  | L4 | CONN2_MODPRS# |  |  |  |  |  |  |
|  | A5 | GND |  | B5 | RFU |  | C5 | GND |  | D5 | S7_TX14N | E5 | GND | F5 | CONN2_MODSEL# | G5 | GND | H5 | RFU | J5 | GND |  | K5 | S7_RX15N |  | L5 | GND |  |  |  |  |  |  |
|  | A6 | GND |  | B6 | RFU |  | C6 | GND |  | D6 | S7_TX14P | E6 | GND | F6 | CONN2_RESET# | G6 | GND | H6 | RFU | J6 | GND |  | K6 | S7_RX15P |  | L6 | GND |  |  |  |  |  |  |
|  | A7 | RFU |  | B7 | GND |  | C7 | RFU |  | D7 | GND | E7 | S7_TX13N | F7 | GND | G7 | RFU | H7 | GND | J7 | S7_RX13N |  | K7 | GND |  | L7 | S7_RX14N |  |  |  |  |  |  |
|  | A8 | RFU |  | B8 | GND |  | C8 | RFU |  | D8 | GND | E8 | S7_TX13P | F8 | GND | G8 | RFU | H8 | GND | J8 | S7_RX13P |  | K8 | GND |  | L8 | S7_RX14P |  |  |  |  |  |  |
|  | A9 | GND |  | B9 | S7_TX7N |  | C9 | GND |  | D9 | S7_TX12N | E9 | GND | F9 | CONN2_GREEN_LED | G9 | GND | H9 | S7_RX7N | J9 | GND |  | K9 | S7_RX12N |  | L9 | GND |  |  |  |  |  |  |
|  | A10 | GND |  | B10 | S7_TX7P |  | C10 | GND |  | D10 | S7_TX12P | E10 | GND | F10 | CONN2_YELLOW_LED | G10 | GND | H10 | S7_RX7P | J10 | GND |  | K10 | S7_RX12P |  | L10 | GND |  |  |  |  |  |  |
|  | A11 | S7_TX5N |  | B11 | GND |  | C11 | S7_TX6N |  | D11 | GND | E11 | S7_TX11N | F11 | GND | G11 | S7_RX5N | H11 | GND | J11 | S7_RX6N |  | K11 | GND |  | L11 | S7_RX11N |  |  |  |  |  |  |
|  | A12 | S7_TX5P |  | B12 | GND |  | C12 | S7_TX6P |  | D12 | GND | E12 | S7_TX11P | F12 | GND | G12 | S7_RX5P | H12 | GND | J12 | S7_RX6P |  | K12 | GND |  | L12 | S7_RX11P |  |  |  |  |  |  |
|  | A13 | GND |  | B13 | S7_TX4N |  | C13 | GND |  | D13 | S7_TX10N | E13 | GND | F13 | TEST10 | G13 | GND | H13 | S7_RX4N | J13 | GND |  | K13 | S7_RX10N |  | L13 | GND |  |  |  |  |  |  |
|  | A14 | GND |  | B14 | S7_TX4P |  | C14 | GND |  | D14 | S7_TX10P | E14 | GND | F14 | TEST11 | G14 | GND | H14 | S7_RX4P | J14 | GND |  | K14 | S7_RX10P |  | L14 | GND |  |  |  |  |  |  |
|  | A15 | S7_TX2N |  | B15 | GND |  | C15 | S7_TX3N |  | D15 | GND | E15 | S7_TX9N | F15 | GND | G15 | S7_RX2N | H15 | GND | J15 | S7_RX3N |  | K15 | GND |  | L15 | S7_RX9N |  |  |  |  |  |  |
|  | A16 | S7_TX2P |  | B16 | GND |  | C16 | S7_TX3P |  | D16 | GND | E16 | S7_TX9P | F16 | GND | G16 | S7_RX2P | H16 | GND | J16 | S7_RX3P |  | K16 | GND |  | L16 | S7_RX9P |  |  |  |  |  |  |
|  | A17 | GND |  | B17 | S7_TX1N |  | C17 | GND |  | D17 | S7_TX8N | E17 | GND | F17 | TEST12 | G17 | GND | H17 | S7_RX1N | J17 | GND |  | K17 | S7_RX8N |  | L17 | GND |  |  |  |  |  |  |
|  | A18 | GND |  | B18 | S7_TX1P |  | C18 | GND |  | D18 | S7_TX8P | E18 | GND | F18 | TEST13 | G18 | GND | H18 | S7_RX1P | J18 | GND |  | K18 | S7_RX8P |  | L18 | GND |  |  |  |  |  |  |
|  | A19 | S7_TX0N |  | B19 | GND |  | C19 | S6_TX0N |  | D19 | GND | E19 | S6_TX8N | F19 | GND | G19 | S7_RX0N | H19 | GND | J19 | S6_RX0N |  | K19 | GND |  | L19 | S6_RX8N |  |  |  |  |  |  |
|  | A20 | S7_TX0P |  | B20 | GND |  | C20 | S6_TX0P |  | D20 | GND | E20 | S6_TX8P | F20 | GND | G20 | S7_RX0P | H20 | GND | J20 | S6_RX0P |  | K20 | GND |  | L20 | S6_RX8P |  |  |  |  |  |  |
|  | A21 | GND |  | B21 | S6_TX1N |  | C21 | GND |  | D21 | S6_TX9N | E21 | GND | F21 | TEST14 | G21 | GND | H21 | S6_RX1N | J21 | GND |  | K21 | S6_RX9N |  | L21 | GND |  |  |  |  |  |  |
|  | A22 | GND |  | B22 | S6_TX1P |  | C22 | GND |  | D22 | S6_TX9P | E22 | GND | F22 | RFU | G22 | GND | H22 | S6_RX1P | J22 | GND |  | K22 | S6_RX9P |  | L22 | GND |  |  |  |  |  |  |
|  | A23 | S6_TX3N |  | B23 | GND |  | C23 | S6_TX2N |  | D23 | GND | E23 | S6_TX10N | F23 | GND | G23 | S6_RX3N | H23 | GND | J23 | S6_RX2N |  | K23 | GND |  | L23 | S6_RX10N |  |  |  |  |  |  |
|  | A24 | S6_TX3P |  | B24 | GND |  | C24 | S6_TX2P |  | D24 | GND | E24 | S6_TX10P | F24 | GND | G24 | S6_RX3P | H24 | GND | J24 | S6_RX2P |  | K24 | GND |  | L24 | S6_RX10P |  |  |  |  |  |  |
|  | A25 | GND |  | B25 | S6_TX4N |  | C25 | GND |  | D25 | S6_TX11N | E25 | GND | F25 | #REF! | G25 | GND | H25 | S6_RX4N | J25 | GND |  | K25 | S6_RX11N |  | L25 | GND |  |  |  |  |  |  |
|  | A26 | GND |  | B26 | S6_TX4P |  | C26 | GND |  | D26 | S6_TX11P | E26 | GND | F26 | #REF! | G26 | GND | H26 | S6_RX4P | J26 | GND |  | K26 | S6_RX11P |  | L26 | GND |  |  |  |  |  |  |
|  | A27 | S6_TX5N |  | B27 | GND |  | C27 | S6_TX13N |  | D27 | GND | E27 | S6_TX12N | F27 | GND | G27 | S6_RX6N | H27 | GND | J27 | S6_RX5N |  | K27 | GND |  | L27 | S6_RX12N |  |  |  |  |  |  |
|  | A28 | S6_TX5P |  | B28 | GND |  | C28 | S6_TX13P |  | D28 | GND | E28 | S6_TX12P | F28 | GND | G28 | S6_RX6P | H28 | GND | J28 | S6_RX5P |  | K28 | GND |  | L28 | S6_RX12P |  |  |  |  |  |  |
|  | A29 | GND |  | B29 | S6_TX6N |  | C29 | GND |  | D29 | S6_TX14N | E29 | GND | F29 | RFU | G29 | GND | H29 | S6_RX7N | J29 | GND |  | K29 | S6_RX13N |  | L29 | GND |  |  |  |  |  |  |
|  | A30 | GND |  | B30 | S6_TX6P |  | C30 | GND |  | D30 | S6_TX14P | E30 | GND | F30 | RFU | G30 | GND | H30 | S6_RX7P | J30 | GND |  | K30 | S6_RX13P |  | L30 | GND |  |  |  |  |  |  |
|  | A31 | S6_TX7N |  | B31 | GND |  | C31 | S6_TX15N |  | D31 | GND | E31 | RFU | F31 | GND | G31 | RFU | H31 | GND | J31 | S6_RX15N |  | K31 | GND |  | L31 | S6_RX14N |  |  |  |  |  |  |
|  | A32 | S6_TX7P |  | B32 | GND |  | C32 | S6_TX15P |  | D32 | GND | E32 | RFU | F32 | GND | G32 | RFU | H32 | GND | J32 | S6_RX15P |  | K32 | GND |  | L32 | S6_RX14P |  |  |  |  |  |  |
|  | A33 | GND |  | B33 | S5_TX0N |  | C33 | GND |  | D33 | S5_TX8N | E33 | GND | F33 | RFU | G33 | GND | H33 | S5_RX0N | J33 | GND |  | K33 | S5_RX8N |  | L33 | GND |  |  |  |  |  |  |
|  | A34 | GND |  | B34 | S5_TX0P |  | C34 | GND |  | D34 | S5_TX8P | E34 | GND | F34 | RFU | G34 | GND | H34 | S5_RX0P | J34 | GND |  | K34 | S5_RX8P |  | L34 | GND |  |  |  |  |  |  |
|  | A35 | S5_TX2N |  | B35 | GND |  | C35 | S5_TX1N |  | D35 | GND | E35 | S5_TX9N | F35 | GND | G35 | S5_RX2N | H35 | GND | J35 | S5_RX1N |  | K35 | GND |  | L35 | S5_RX9N |  |  |  |  |  |  |
|  | A36 | S5_TX2P |  | B36 | GND |  | C36 | S5_TX1P |  | D36 | GND | E36 | S5_TX9P | F36 | GND | G36 | S5_RX2P | H36 | GND | J36 | S5_RX1P |  | K36 | GND |  | L36 | S5_RX9P |  |  |  |  |  |  |
|  | A37 | GND |  | B37 | S5_TX3N |  | C37 | GND |  | D37 | S5_TX10N | E37 | GND | F37 | RFU | G37 | GND | H37 | S5_RX3N | J37 | GND |  | K37 | S5_RX10N |  | L37 | GND |  |  |  |  |  |  |
|  | A38 | GND |  | B38 | S5_TX3P |  | C38 | GND |  | D38 | S5_TX10P | E38 | GND | F38 | RFU | G38 | GND | H38 | S5_RX3P | J38 | GND |  | K38 | S5_RX10P |  | L38 | GND |  |  |  |  |  |  |
|  | A39 | S5_TX4N |  | B39 | GND |  | C39 | S5_TX11N |  | D39 | GND | E39 | RFU | F39 | GND | G39 | S5_RX5N | H39 | GND | J39 | S5_RX4N |  | K39 | GND |  | L39 | S5_RX11N |  |  |  |  |  |  |
|  | A40 | S5_TX4P |  | B40 | GND |  | C40 | S5_TX11P |  | D40 | GND | E40 | RFU | F40 | GND | G40 | S5_RX5P | H40 | GND | J40 | S5_RX4P |  | K40 | GND |  | L40 | S5_RX11P |  |  |  |  |  |  |
|  | A41 | GND |  | B41 | S5_TX5N |  | C41 | GND |  | D41 | S5_TX12N | E41 | GND | F41 | RFU | G41 | GND | H41 | S5_RX6N | J41 | GND |  | K41 | S5_RX12N |  | L41 | GND |  |  |  |  |  |  |
|  | A42 | GND |  | B42 | S5_TX5P |  | C42 | GND |  | D42 | S5_TX12P | E42 | GND | F42 | RFU | G42 | GND | H42 | S5_RX6P | J42 | GND |  | K42 | S5_RX12P |  | L42 | GND |  |  |  |  |  |  |
|  | A43 | S5_TX6N |  | B43 | GND |  | C43 | S5_TX14N |  | D43 | GND | E43 | S5_TX13N | F43 | GND | G43 | S5_RX7N | H43 | GND | J43 | S5_RX14N |  | K43 | GND |  | L43 | S5_RX13N |  |  |  |  |  |  |
|  | A44 | S5_TX6P |  | B44 | GND |  | C44 | S5_TX14P |  | D44 | GND | E44 | S5_TX13P | F44 | GND | G44 | S5_RX7P | H44 | GND | J44 | S5_RX14P |  | K44 | GND |  | L44 | S5_RX13P |  |  |  |  |  |  |
|  | A45 | GND |  | B45 | S5_TX7N |  | C45 | GND |  | D45 | S5_TX15N | E45 | GND | F45 | RFU | G45 | GND | H45 | AUX_156M_REFCLKP | J45 | GND |  | K45 | S5_RX15N |  | L45 | GND |  |  |  |  |  |  |
|  | A46 | GND |  | B46 | S5_TX7P |  | C46 | GND |  | D46 | S5_TX15P | E46 | GND | F46 | LINK_CONFIG[4] | G46 | GND | H46 | AUX_156M_REFCLKN | J46 | GND |  | K46 | S5_RX15P |  | L46 | GND |  |  |  |  |  |  |
|  | A47 | S4_TX1N |  | B47 | GND |  | C47 | S4_TX0N |  | D47 | GND | E47 | S4_TX8N | F47 | GND | G47 | S4_RX0N | H47 | GND | J47 | S4_RX9N |  | K47 | GND |  | L47 | S4_RX8N |  |  |  |  |  |  |
|  | A48 | S4_TX1P |  | B48 | GND |  | C48 | S4_TX0P |  | D48 | GND | E48 | S4_TX8P | F48 | GND | G48 | S4_RX0P | H48 | GND | J48 | S4_RX9P |  | K48 | GND |  | L48 | S4_RX8P |  |  |  |  |  |  |
|  | A49 | GND |  | B49 | S4_TX2N |  | C49 | GND |  | D49 | S4_TX9N | E49 | GND | F49 | LINK_CONFIG[3] | G49 | GND | H49 | S4_RX1N | J49 | GND |  | K49 | S4_RX10N |  | L49 | GND |  |  |  |  |  |  |
|  | A50 | GND |  | B50 | S4_TX2P |  | C50 | GND |  | D50 | S4_TX9P | E50 | GND | F50 | LINK_CONFIG[2] | G50 | GND | H50 | S4_RX1P | J50 | GND |  | K50 | S4_RX10P |  | L50 | GND |  |  |  |  |  |  |
|  | A51 | S4_TX3N |  | B51 | GND |  | C51 | S4_TX11N |  | D51 | GND | E51 | S4_TX10N | F51 | GND | G51 | S4_RX2N | H51 | GND | J51 | S4_RX12N |  | K51 | GND |  | L51 | S4_RX11N |  |  |  |  |  |  |
|  | A52 | S4_TX3P |  | B52 | GND |  | C52 | S4_TX11P |  | D52 | GND | E52 | S4_TX10P | F52 | GND | G52 | S4_RX2P | H52 | GND | J52 | S4_RX12P |  | K52 | GND |  | L52 | S4_RX11P |  |  |  |  |  |  |
|  | A53 | GND |  | B53 | S4_TX4N |  | C53 | GND |  | D53 | S4_TX12N | E53 | GND | F53 | LINK_CONFIG[1] | G53 | GND | H53 | S4_RX3N | J53 | GND |  | K53 | S4_RX13N |  | L53 | GND |  |  |  |  |  |  |
|  | A54 | GND |  | B54 | S4_TX4P |  | C54 | GND |  | D54 | S4_TX12P | E54 | GND | F54 | LINK_CONFIG[0] | G54 | GND | H54 | S4_RX3P | J54 | GND |  | K54 | S4_RX13P |  | L54 | GND |  |  |  |  |  |  |
|  | A55 | S4_TX5N |  | B55 | GND |  | C55 | S4_TX14N |  | D55 | GND | E55 | S4_TX13N | F55 | GND | G55 | SCALE_DEBUG_EN | H55 | GND | J55 | S4_RX4N |  | K55 | GND |  | L55 | S4_RX14N |  |  |  |  |  |  |
|  | A56 | S4_TX5P |  | B56 | GND |  | C56 | S4_TX14P |  | D56 | GND | E56 | S4_TX13P | F56 | GND | G56 | DEBUG_PORT_PRSNT# | H56 | GND | J56 | S4_RX4P |  | K56 | GND |  | L56 | S4_RX14P |  |  |  |  |  |  |
|  | A57 | GND |  | B57 | S4_TX6N |  | C57 | GND |  | D57 | S4_TX15N | E57 | GND | F57 | PLINK_CAP | G57 | GND | H57 | S4_RX5N | J57 | GND |  | K57 | S4_RX15N |  | L57 | GND |  |  |  |  |  |  |
|  | A58 | GND |  | B58 | S4_TX6P |  | C58 | GND |  | D58 | S4_TX15P | E58 | GND | F58 | DWN_PERST# | G58 | GND | H58 | S4_RX5P | J58 | GND |  | K58 | S4_RX15P |  | L58 | GND |  |  |  |  |  |  |
|  | A59 | S4_TX7N |  | B59 | GND |  | C59 | RFU |  | D59 | GND | E59 | DWN_REFCLKP | F59 | GND | G59 | S4_RX7N | H59 | GND | J59 | S4_RX6N |  | K59 | GND |  | L59 | JTAG1 _TRST |  |  |  |  |  |  |
|  | A60 | S4_TX7P |  | B60 | GND |  | C60 | RFU |  | D60 | GND | E60 | DWN_REFCLKN | F60 | GND | G60 | S4_RX7P | H60 | GND | J60 | S4_RX6P |  | K60 | GND |  | L60 | JTAG1 _TMS |  |  |  |  |  |  |
|  | A61 | GND |  | B61 | PE_BIF[1] |  | C61 | GND |  | D61 | MNGMT_LINK0TN | E61 | GND | F61 | AUX_100M_REFCLKP | G61 | GND | H61 | MNGMT_LINK0RN | J61 | GND |  | K61 | JTAG1 _TCK |  | L61 | GND |  |  |  |  |  |  |
|  | A62 | GND |  | B62 | PE_BIF[0] |  | C62 | GND |  | D62 | MNGMT_LINK0TP | E62 | GND | F62 | AUX_100M_REFCLKN | G62 | GND | H62 | MNGMT_LINK0RP | J62 | GND |  | K62 | JTAG1 _TDO |  | L62 | GND |  |  |  |  |  |  |
|  |  |  |  |  |  |  | C63 | PRSNT1# |  | D63 | GND | E63 | MNGMT_LINK1TP | F63 | GND | G63 | MNGMT_LINK1RP | H63 | GND | J63 | JTAG1 _TDI |  |  |  |  |  |  |  |  |  |  |  |  |
|  |  |  |  |  |  |  | C64 | THERMTRIP# |  | D64 | GND | E64 | MNGMT_LINK1TN | F64 | GND | G64 | MNGMT_LINK1RN | H64 | GND | J64 | RFU |  |  |  |  |  |  |  |  |  |  |  |  |
|  | CONNECTOR #0 (P48V, P12V, PCIE, Link 1,2,3) |  |  |  | CONNECTOR #1 (Link 4,5,6,7) |  |  |  |  |  |  |  |  |  |  |  |  |  |  |  |  |  |  |  |  |  |  |  |  |  |  |  |  |
|  | P48V | 16 |  |  | S7_*X* | 64 |  |  |  |  |  |  |  |  |  |  |  |  |  |  |  |  |  |  |  |  |  |  |  |  |  |  |  |
|  | P12V1 | 5 |  |  | S4_*X* | 64 |  |  |  |  |  |  |  |  |  |  |  |  |  |  |  |  |  |  |  |  |  |  |  |  |  |  |  |
|  | P12V2 | 27 |  |  | S5_*X* | 64 |  |  |  |  |  |  |  |  |  |  |  |  |  |  |  |  |  |  |  |  |  |  |  |  |  |  |  |
|  | P3V3 | 2 |  |  | S6_*X* | 64 |  |  |  |  |  |  |  |  |  |  |  |  |  |  |  |  |  |  |  |  |  |  |  |  |  |  |  |
|  | PVREF | 2 |  |  | GND | 344 |  |  |  |  |  |  |  |  |  |  |  |  |  |  |  |  |  |  |  |  |  |  |  |  |  |  |  |
|  | GND | 334 |  |  | *CLK* | 6 |  |  |  |  |  |  |  |  |  |  |  |  |  |  |  |  |  |  |  |  |  |  |  |  |  |  |  |
|  | S1_*X* | 64 |  |  | CONN* | 14 |  |  |  |  |  |  |  |  |  |  |  |  |  |  |  |  |  |  |  |  |  |  |  |  |  |  |  |
|  | S2_*X* | 64 |  |  | PLINK_CAP | 1 |  |  |  |  |  |  |  |  |  |  |  |  |  |  |  |  |  |  |  |  |  |  |  |  |  |  |  |
|  | S3_*X* | 64 |  |  | *RST#* | 1 |  |  |  |  |  |  |  |  |  |  |  |  |  |  |  |  |  |  |  |  |  |  |  |  |  |  |  |
|  | PCIE_*X* | 64 |  |  | JTAG* | 5 |  |  |  |  |  |  |  |  |  |  |  |  |  |  |  |  |  |  |  |  |  |  |  |  |  |  |  |
|  | PE_REFCLK* | 2 |  |  | PRSNT* | 1 |  |  |  |  |  |  |  |  |  |  |  |  |  |  |  |  |  |  |  |  |  |  |  |  |  |  |  |
|  | *RST#* | 2 |  |  | THERMTRIP# | 1 |  |  |  |  |  |  |  |  |  |  |  |  |  |  |  |  |  |  |  |  |  |  |  |  |  |  |  |
|  | *PWRGD* | 2 |  |  | PE_BIF* | 2 |  |  |  |  |  |  |  |  |  |  |  |  |  |  |  |  |  |  |  |  |  |  |  |  |  |  |  |
|  | PWRBRK# | 1 |  |  | TEST* | 5 |  |  |  |  |  |  |  |  |  |  |  |  |  |  |  |  |  |  |  |  |  |  |  |  |  |  |  |
|  | *I2C/SMBus* | 0 |  |  | LINK_CONFIG* | 5 |  |  |  |  |  |  |  |  |  |  |  |  |  |  |  |  |  |  |  |  |  |  |  |  |  |  |  |
|  | UART* | 2 |  |  | *DEBUG* | 2 |  |  |  |  |  |  |  |  |  |  |  |  |  |  |  |  |  |  |  |  |  |  |  |  |  |  |  |
|  | PRSNT* | 1 |  |  | *MNGMT* | 8 |  |  |  |  |  |  |  |  |  |  |  |  |  |  |  |  |  |  |  |  |  |  |  |  |  |  |  |
|  | MODULE_ID* | 5 |  |  | *PWRRDT* | 2 |  |  |  |  |  |  |  |  |  |  |  |  |  |  |  |  |  |  |  |  |  |  |  |  |  |  |  |
|  | JTAG* | 5 |  |  | RFU | 35 |  |  |  |  |  |  |  |  |  |  |  |  |  |  |  |  |  |  |  |  |  |  |  |  |  |  |  |
|  | TEST* | 11 |  |  | TOTAL | 688 |  |  |  |  |  |  |  |  |  |  |  |  |  |  |  |  |  |  |  |  |  |  |  |  |  |  |  |
|  | MANF_MODE# | 1 |  |  |  |  |  |  |  |  |  |  |  |  |  |  |  |  |  |  |  |  |  |  |  |  |  |  |  |  |  |  |  |
|  | FW_RECOVERY# | 1 |  |  |  |  |  |  |  |  |  |  |  |  |  |  |  |  |  |  |  |  |  |  |  |  |  |  |  |  |  |  |  |
|  | RFU | 4 |  |  |  |  |  |  |  |  |  |  |  |  |  |  |  |  |  |  |  |  |  |  |  |  |  |  |  |  |  |  |  |
|  | DO_NOT_USE | 4 |  |  |  |  |  |  |  |  |  |  |  |  |  |  |  |  |  |  |  |  |  |  |  |  |  |  |  |  |  |  |  |
|  | TOTAL | 683 |  |  |  |  |  |  |  |  |  |  |  |  |  |  |  |  |  |  |  |  |  |  |  |  |  |  |  |  |  |  |  |
